FILE_TYPE = CONNECTIVITY;
{Allegro Design Entry HDL 17.4-2019 S026 (4007227) 1/17/2022}
"PAGE_NUMBER" = 107;
0"NC";
1"GND\g";
2"GND\g";
3"P3V3\g";
4"M_K_CPU1_SA_DQS_DP<9:0>";
5"M_K_CPU1_SB_DQS_DP<9:0>";
6"M_K_CPU1_SB_DQS_DN<9:0>";
7"M_K_CPU1_SA_DQS_DN<9:0>";
8"M_K_CPU1_SB_DQ<31:0>";
9"M_K_CPU1_SA_DQ<31:0>";
10"M_K_CPU1_SB_CB<7:0>";
11"M_K_CPU1_SA_CB<7:0>";
12"M_K_CPU1_SB_CA<6:0>";
13"M_K_CPU1_SA_CA<6:0>";
14"M_K_CPU1_SB_CB<3>";
15"M_K_CPU1_SA_DQ<31>";
16"M_K_CPU1_SA_CB<7>";
17"M_K_CPU1_SA_CB<4>";
18"M_K_CPU1_SA_CB<1>";
19"M_K_CPU1_SB_CB<7>";
20"M_K_CPU1_SA_CA<0>";
21"M_K_CPU1_SB_CA<0>";
22"M_K_CPU1_SA_CA<1>";
23"M_K_CPU1_SB_CA<1>";
24"M_K_CPU1_SA_CA<2>";
25"M_K_CPU1_SB_CA<2>";
26"M_K_CPU1_SA_CA<3>";
27"M_K_CPU1_SB_CA<3>";
28"M_K_CPU1_SA_CA<4>";
29"M_K_CPU1_SB_CA<4>";
30"M_K_CPU1_SA_CA<5>";
31"M_K_CPU1_SB_CA<5>";
32"M_K_CPU1_SA_CA<6>";
33"M_K_CPU1_SB_CA<6>";
34"M_K_CPU1_SA_CB<6>";
35"M_K_CPU1_SA_CB<5>";
36"M_K_CPU1_SA_CB<3>";
37"M_K_CPU1_SA_CB<2>";
38"M_K_CPU1_SA_CB<0>";
39"M_K_CPU1_SB_CB<6>";
40"M_K_CPU1_SB_CB<5>";
41"M_K_CPU1_SB_CB<4>";
42"M_K_CPU1_SB_CB<2>";
43"M_K_CPU1_SB_CB<1>";
44"M_K_CPU1_SB_CB<0>";
45"M_K_CPU1_CLK_DN<0>";
46"M_K_CPU1_CLK_DP<0>";
47"M_K_CPU1_SA_CS_N<0>";
48"M_K_CPU1_SB_CS_N<0>";
49"M_K_CPU1_SA_CS_N<1>";
50"M_K_CPU1_SB_CS_N<1>";
51"M_K_CPU1_SA_DQ<30>";
52"M_K_CPU1_SA_DQ<29>";
53"M_K_CPU1_SA_DQ<28>";
54"M_K_CPU1_SA_DQ<27>";
55"M_K_CPU1_SA_DQ<26>";
56"M_K_CPU1_SA_DQ<25>";
57"M_K_CPU1_SA_DQ<24>";
58"M_K_CPU1_SA_DQ<23>";
59"M_K_CPU1_SA_DQ<22>";
60"M_K_CPU1_SA_DQ<21>";
61"M_K_CPU1_SA_DQ<20>";
62"M_K_CPU1_SA_DQ<19>";
63"M_K_CPU1_SA_DQ<18>";
64"M_K_CPU1_SA_DQ<17>";
65"M_K_CPU1_SA_DQ<16>";
66"M_K_CPU1_SA_DQ<15>";
67"M_K_CPU1_SA_DQ<14>";
68"M_K_CPU1_SA_DQ<13>";
69"M_K_CPU1_SA_DQ<12>";
70"M_K_CPU1_SA_DQ<11>";
71"M_K_CPU1_SA_DQ<10>";
72"M_K_CPU1_SA_DQ<9>";
73"M_K_CPU1_SA_DQ<8>";
74"M_K_CPU1_SA_DQ<7>";
75"M_K_CPU1_SA_DQ<6>";
76"M_K_CPU1_SA_DQ<5>";
77"M_K_CPU1_SA_DQ<4>";
78"M_K_CPU1_SA_DQ<3>";
79"M_K_CPU1_SA_DQ<2>";
80"M_K_CPU1_SA_DQ<1>";
81"M_K_CPU1_SA_DQ<0>";
82"M_K_CPU1_SB_DQ<31>";
83"M_K_CPU1_SB_DQ<30>";
84"M_K_CPU1_SB_DQ<29>";
85"M_K_CPU1_SB_DQ<28>";
86"M_K_CPU1_SB_DQ<27>";
87"M_K_CPU1_SB_DQ<26>";
88"M_K_CPU1_SB_DQ<25>";
89"M_K_CPU1_SB_DQ<24>";
90"M_K_CPU1_SB_DQ<23>";
91"M_K_CPU1_SB_DQ<22>";
92"M_K_CPU1_SB_DQ<21>";
93"M_K_CPU1_SB_DQ<20>";
94"M_K_CPU1_SB_DQ<19>";
95"M_K_CPU1_SB_DQ<18>";
96"M_K_CPU1_SB_DQ<17>";
97"M_K_CPU1_SB_DQ<16>";
98"M_K_CPU1_SB_DQ<15>";
99"M_K_CPU1_SB_DQ<14>";
100"M_K_CPU1_SB_DQ<13>";
101"M_K_CPU1_SB_DQ<12>";
102"M_K_CPU1_SB_DQ<11>";
103"M_K_CPU1_SB_DQ<10>";
104"M_K_CPU1_SB_DQ<9>";
105"M_K_CPU1_SB_DQ<8>";
106"M_K_CPU1_SB_DQ<7>";
107"M_K_CPU1_SB_DQ<6>";
108"M_K_CPU1_SB_DQ<5>";
109"M_K_CPU1_SB_DQ<4>";
110"M_K_CPU1_SB_DQ<3>";
111"M_K_CPU1_SB_DQ<2>";
112"M_K_CPU1_SB_DQ<1>";
113"M_K_CPU1_SB_DQ<0>";
114"M_K_CPU1_SA_RSP<0>";
115"M_K_CPU1_SB_RSP<0>";
116"M_K_CPU1_SA_PAR";
117"M_K_CPU1_SB_PAR";
118"M_K_CPU1_SA_DQS_DN<7>";
119"M_K_CPU1_SA_DQS_DP<6>";
120"M_K_CPU1_SB_DQS_DP<8>";
121"M_K_CPU1_SB_DQS_DN<8>";
122"M_K_CPU1_SB_DQS_DP<7>";
123"M_K_CPU1_SA_DQS_DN<0>";
124"M_K_CPU1_SA_DQS_DP<0>";
125"M_K_CPU1_SB_DQS_DN<0>";
126"M_K_CPU1_SB_DQS_DP<0>";
127"M_K_CPU1_SA_DQS_DN<1>";
128"M_K_CPU1_SA_DQS_DP<1>";
129"M_K_CPU1_SB_DQS_DN<1>";
130"M_K_CPU1_SB_DQS_DP<1>";
131"M_K_CPU1_SA_DQS_DN<2>";
132"M_K_CPU1_SA_DQS_DP<2>";
133"M_K_CPU1_SB_DQS_DN<2>";
134"M_K_CPU1_SB_DQS_DP<2>";
135"M_K_CPU1_SA_DQS_DN<3>";
136"M_K_CPU1_SA_DQS_DP<3>";
137"M_K_CPU1_SB_DQS_DN<3>";
138"M_K_CPU1_SB_DQS_DP<3>";
139"M_K_CPU1_SA_DQS_DN<4>";
140"M_K_CPU1_SA_DQS_DP<4>";
141"M_K_CPU1_SB_DQS_DN<4>";
142"M_K_CPU1_SB_DQS_DP<4>";
143"M_K_CPU1_SA_DQS_DN<5>";
144"M_K_CPU1_SA_DQS_DP<5>";
145"M_K_CPU1_SB_DQS_DN<5>";
146"M_K_CPU1_SB_DQS_DP<5>";
147"M_K_CPU1_SA_DQS_DN<6>";
148"M_K_CPU1_SB_DQS_DN<6>";
149"M_K_CPU1_SB_DQS_DP<6>";
150"M_K_CPU1_SA_DQS_DP<7>";
151"M_K_CPU1_SB_DQS_DN<7>";
152"M_K_CPU1_SA_DQS_DN<8>";
153"M_K_CPU1_SA_DQS_DP<8>";
154"M_K_CPU1_SA_DQS_DN<9>";
155"M_K_CPU1_SB_DQS_DN<9>";
156"M_K_CPU1_SB_DQS_DP<9>";
157"M_K_CPU1_SA_DQS_DP<9>";
158"PD_CHK_CPU1_DIMM_SAA";
159"PWRGD_CHGL_CPU1";
160"M_K_CPU1_RESET_N";
161"M_K_CPU1_ALERT_N";
162"PD_CHK_CPU1_DIMM_SAA";
163"P3V3_AUX\g";
164"P12V_MEM_CPU1\g";
165"GND\g";
166"GND\g";
167"GND\g";
168"I3C_SPD_DDRK_CPU1_SCL";
169"I3C_SPD_DDRK_CPU1_SDA";
170"I3C_SPD_DDRGL_CPU1_SDA";
171"PWRGD_CHK_CPU1_DIMM";
172"I3C_SPD_DDRGL_CPU1_SCL";
%"TAP"
"1","(-6000,4175)","0","mstr_standard","I100";
;
CDS_LIB"mstr_standard"
BODY_TYPE"PLUMBING"
HDL_TAP"TRUE";
"B \NAC \NWC"9;
"S \NAC"
BN"8"73;
%"TAP"
"1","(-6000,4225)","0","mstr_standard","I101";
;
CDS_LIB"mstr_standard"
BODY_TYPE"PLUMBING"
HDL_TAP"TRUE";
"B \NAC \NWC"9;
"S \NAC"
BN"9"72;
%"TAP"
"1","(-6000,4275)","0","mstr_standard","I102";
;
CDS_LIB"mstr_standard"
BODY_TYPE"PLUMBING"
HDL_TAP"TRUE";
"B \NAC \NWC"9;
"S \NAC"
BN"10"71;
%"TAP"
"1","(-6000,4375)","0","mstr_standard","I103";
;
CDS_LIB"mstr_standard"
BODY_TYPE"PLUMBING"
HDL_TAP"TRUE";
"B \NAC \NWC"9;
"S \NAC"
BN"12"69;
%"TAP"
"1","(-6000,4325)","0","mstr_standard","I104";
;
CDS_LIB"mstr_standard"
BODY_TYPE"PLUMBING"
HDL_TAP"TRUE";
"B \NAC \NWC"9;
"S \NAC"
BN"11"70;
%"TAP"
"1","(-6000,4425)","0","mstr_standard","I105";
;
CDS_LIB"mstr_standard"
BODY_TYPE"PLUMBING"
HDL_TAP"TRUE";
"B \NAC \NWC"9;
"S \NAC"
BN"13"68;
%"TAP"
"1","(-6000,4475)","0","mstr_standard","I106";
;
CDS_LIB"mstr_standard"
BODY_TYPE"PLUMBING"
HDL_TAP"TRUE";
"B \NAC \NWC"9;
"S \NAC"
BN"14"67;
%"TAP"
"1","(-6000,4525)","0","mstr_standard","I107";
;
CDS_LIB"mstr_standard"
BODY_TYPE"PLUMBING"
HDL_TAP"TRUE";
"B \NAC \NWC"9;
"S \NAC"
BN"15"66;
%"TAP"
"1","(-6000,4575)","0","mstr_standard","I108";
;
CDS_LIB"mstr_standard"
BODY_TYPE"PLUMBING"
HDL_TAP"TRUE";
"B \NAC \NWC"9;
"S \NAC"
BN"16"65;
%"TAP"
"1","(-6000,4675)","0","mstr_standard","I109";
;
CDS_LIB"mstr_standard"
BODY_TYPE"PLUMBING"
HDL_TAP"TRUE";
"B \NAC \NWC"9;
"S \NAC"
BN"18"63;
%"TAP"
"1","(-6000,4625)","0","mstr_standard","I110";
;
CDS_LIB"mstr_standard"
BODY_TYPE"PLUMBING"
HDL_TAP"TRUE";
"B \NAC \NWC"9;
"S \NAC"
BN"17"64;
%"TAP"
"1","(-6000,4725)","0","mstr_standard","I111";
;
CDS_LIB"mstr_standard"
BODY_TYPE"PLUMBING"
HDL_TAP"TRUE";
"B \NAC \NWC"9;
"S \NAC"
BN"19"62;
%"TAP"
"1","(-6000,4775)","0","mstr_standard","I112";
;
CDS_LIB"mstr_standard"
BODY_TYPE"PLUMBING"
HDL_TAP"TRUE";
"B \NAC \NWC"9;
"S \NAC"
BN"20"61;
%"TAP"
"1","(-6000,4825)","0","mstr_standard","I113";
;
CDS_LIB"mstr_standard"
BODY_TYPE"PLUMBING"
HDL_TAP"TRUE";
"B \NAC \NWC"9;
"S \NAC"
BN"21"60;
%"TAP"
"1","(-6000,4875)","0","mstr_standard","I114";
;
CDS_LIB"mstr_standard"
BODY_TYPE"PLUMBING"
HDL_TAP"TRUE";
"B \NAC \NWC"9;
"S \NAC"
BN"22"59;
%"TAP"
"1","(-6000,4925)","0","mstr_standard","I115";
;
CDS_LIB"mstr_standard"
BODY_TYPE"PLUMBING"
HDL_TAP"TRUE";
"B \NAC \NWC"9;
"S \NAC"
BN"23"58;
%"TAP"
"1","(-6000,4975)","0","mstr_standard","I116";
;
CDS_LIB"mstr_standard"
BODY_TYPE"PLUMBING"
HDL_TAP"TRUE";
"B \NAC \NWC"9;
"S \NAC"
BN"24"57;
%"TAP"
"1","(-6000,5025)","0","mstr_standard","I117";
;
CDS_LIB"mstr_standard"
BODY_TYPE"PLUMBING"
HDL_TAP"TRUE";
"B \NAC \NWC"9;
"S \NAC"
BN"25"56;
%"TAP"
"1","(-6000,5075)","0","mstr_standard","I118";
;
CDS_LIB"mstr_standard"
BODY_TYPE"PLUMBING"
HDL_TAP"TRUE";
"B \NAC \NWC"9;
"S \NAC"
BN"26"55;
%"TAP"
"1","(-6000,5125)","0","mstr_standard","I119";
;
CDS_LIB"mstr_standard"
BODY_TYPE"PLUMBING"
HDL_TAP"TRUE";
"B \NAC \NWC"9;
"S \NAC"
BN"27"54;
%"TAP"
"1","(-6000,5175)","0","mstr_standard","I120";
;
CDS_LIB"mstr_standard"
BODY_TYPE"PLUMBING"
HDL_TAP"TRUE";
"B \NAC \NWC"9;
"S \NAC"
BN"28"53;
%"TAP"
"1","(-6000,5275)","0","mstr_standard","I121";
;
CDS_LIB"mstr_standard"
BODY_TYPE"PLUMBING"
HDL_TAP"TRUE";
"B \NAC \NWC"9;
"S \NAC"
BN"30"51;
%"TAP"
"1","(-6000,5325)","0","mstr_standard","I122";
;
CDS_LIB"mstr_standard"
BODY_TYPE"PLUMBING"
HDL_TAP"TRUE";
"B \NAC \NWC"9;
"S \NAC"
BN"31"15;
%"TAP"
"1","(-6000,5225)","0","mstr_standard","I123";
;
CDS_LIB"mstr_standard"
BODY_TYPE"PLUMBING"
HDL_TAP"TRUE";
"B \NAC \NWC"9;
"S \NAC"
BN"29"52;
%"GND"
"1","(-6400,875)","0","mstr_symbols","I126";
;
BOM_COST"MEM"
SIZE"1B"
CDS_LIB"mstr_symbols"
VOLTAGE"0.0"
BODY_TYPE"PLUMBING"
HDL_POWER"GND";
"A\NAC"1;
%"Q_RES"
"2","(-6400,1100)","0","pure_quanta","I136";
;
LOCATION"R777"
$SEC"1"
CDS_SEC"1"
PACK_TYPE"0402LF"
VALUE"54.9K"
TOLERANCE"1%"
MATERIAL"CHIP"
WATTAGE"1/16W"
CDS_LIB"pure_quanta"
PART_NUMBER"CS35492FB03";
"A"
$PN"1"158;
"B"
$PN"2"1;
%"GND"
"1","(-2150,1850)","0","mstr_symbols","I137";
;
CDS_LIB"mstr_symbols"
SIZE"1B"
VOLTAGE"0.0"
BODY_TYPE"PLUMBING"
HDL_POWER"GND";
"A\NAC"167;
%"GND"
"1","(-350,1625)","0","mstr_symbols","I138";
;
CDS_LIB"mstr_symbols"
SIZE"1B"
VOLTAGE"0.0"
BODY_TYPE"PLUMBING"
HDL_POWER"GND";
"A\NAC"166;
%"SCONN288_DDR506112002KQ"
"3","(-1250,3625)","0","pure_quanta","I139";
;
LOCATION"J99"
$SEC"3"
CDS_SEC"3"
VALUE"SCONN288_DDR506112002KQ"
PART_TYPE"SMLF"
MATERIAL"IO"
CDS_LMAN_SYM_OUTLINE"-450,1800,450,-1750"
NEEDS_NO_SIZE"TRUE"
CDS_LIB"pure_quanta"
PART_NUMBER"DFHST8FS479";
"G3"
$PN"G3"166;
"G2"
$PN"G2"166;
"G1"
$PN"G1"166;
"VSS62"
$PN"141"166;
"VSS61"
$PN"139"166;
"VSS60"
$PN"136"166;
"VSS58"
$PN"132"166;
"VSS104"
$PN"240"167;
"VSS102"
$PN"235"167;
"VSS100"
$PN"230"167;
"VIN_BULK2"
$PN"146"164;
"VIN_BULK1"
$PN"145"164;
"VIN_BULK0"
$PN"1"164;
"VSS126"
$PN"288"167;
"VSS125"
$PN"286"167;
"VSS124"
$PN"284"167;
"VSS123"
$PN"281"167;
"VSS122"
$PN"279"167;
"VSS121"
$PN"277"167;
"VSS120"
$PN"275"167;
"VSS119"
$PN"273"167;
"VSS118"
$PN"270"167;
"VSS117"
$PN"268"167;
"VSS116"
$PN"266"167;
"VSS115"
$PN"264"167;
"VSS114"
$PN"262"167;
"VSS113"
$PN"259"167;
"VSS112"
$PN"257"167;
"VSS111"
$PN"255"167;
"VSS110"
$PN"253"167;
"VSS109"
$PN"251"167;
"VSS108"
$PN"248"167;
"VSS107"
$PN"246"167;
"VSS106"
$PN"244"167;
"VSS105"
$PN"242"167;
"VSS103"
$PN"237"167;
"VSS101"
$PN"233"167;
"VSS99"
$PN"228"167;
"VSS98"
$PN"226"167;
"VSS97"
$PN"224"167;
"VSS96"
$PN"222"167;
"VSS95"
$PN"219"167;
"VSS94"
$PN"216"167;
"VSS93"
$PN"214"167;
"VSS92"
$PN"212"167;
"VSS91"
$PN"210"167;
"VSS90"
$PN"208"167;
"VSS89"
$PN"206"167;
"VSS88"
$PN"204"167;
"VSS87"
$PN"202"167;
"VSS86"
$PN"199"167;
"VSS85"
$PN"197"167;
"VSS84"
$PN"195"167;
"VSS83"
$PN"193"167;
"VSS82"
$PN"191"167;
"VSS81"
$PN"188"167;
"VSS80"
$PN"186"167;
"VSS79"
$PN"184"167;
"VSS78"
$PN"182"167;
"VSS77"
$PN"180"167;
"VSS76"
$PN"177"167;
"VSS75"
$PN"175"167;
"VSS74"
$PN"173"167;
"VSS73"
$PN"171"167;
"VSS72"
$PN"169"167;
"VSS71"
$PN"166"167;
"VSS70"
$PN"164"167;
"VSS69"
$PN"162"167;
"VSS68"
$PN"160"167;
"VSS67"
$PN"158"167;
"VSS66"
$PN"155"167;
"VSS65"
$PN"153"167;
"VSS64"
$PN"151"167;
"VSS63"
$PN"143"166;
"VSS59"
$PN"134"166;
"VSS57"
$PN"130"166;
"VSS56"
$PN"128"166;
"VSS55"
$PN"125"166;
"VSS54"
$PN"123"166;
"VSS53"
$PN"121"166;
"VSS52"
$PN"119"166;
"VSS51"
$PN"117"166;
"VSS50"
$PN"114"166;
"VSS49"
$PN"112"166;
"VSS48"
$PN"110"166;
"VSS47"
$PN"108"166;
"VSS46"
$PN"106"166;
"VSS45"
$PN"103"166;
"VSS44"
$PN"101"166;
"VSS43"
$PN"99"166;
"VSS42"
$PN"97"166;
"VSS41"
$PN"95"166;
"VSS40"
$PN"92"166;
"VSS39"
$PN"90"166;
"VSS38"
$PN"88"166;
"VSS37"
$PN"85"166;
"VSS36"
$PN"83"166;
"VSS35"
$PN"81"166;
"VSS34"
$PN"79"166;
"VSS33"
$PN"77"166;
"VSS32"
$PN"75"166;
"VSS31"
$PN"73"166;
"VSS30"
$PN"71"166;
"VSS29"
$PN"69"166;
"VSS28"
$PN"67"166;
"VSS27"
$PN"65"166;
"VSS26"
$PN"63"166;
"VSS25"
$PN"61"166;
"VSS24"
$PN"59"166;
"VSS23"
$PN"57"166;
"VSS22"
$PN"54"166;
"VSS21"
$PN"52"166;
"VSS20"
$PN"50"166;
"VSS19"
$PN"48"166;
"VSS18"
$PN"46"166;
"VSS17"
$PN"43"166;
"VSS16"
$PN"41"166;
"VSS15"
$PN"39"166;
"VSS14"
$PN"37"166;
"VSS13"
$PN"35"166;
"VSS12"
$PN"32"166;
"VSS11"
$PN"30"166;
"VSS10"
$PN"28"166;
"VSS9"
$PN"26"166;
"VSS8"
$PN"24"166;
"VSS7"
$PN"21"166;
"VSS6"
$PN"19"166;
"VSS5"
$PN"17"166;
"VSS4"
$PN"15"166;
"VSS3"
$PN"13"166;
"VSS2"
$PN"10"166;
"VSS1"
$PN"8"166;
"VSS0"
$PN"6"166;
%"Q_CAP"
"1","(-8675,3150)","2","pure_quanta","I185";
;
LOCATION"C176"
$SEC"1"
CDS_SEC"1"
VALUE"0.1UF"
VOLTAGE"25V"
MATERIAL"X7R"
PACK_TYPE"0402"
TOLERANCE"10%"
BOM_COST"MEM"
CDS_LIB"pure_quanta"
ROOM""
PART_NUMBER"CH4104K1B00";
"B"
$PN"2"2;
"A"
$PN"1"163;
%"GND"
"1","(-8675,2925)","0","mstr_symbols","I186";
;
CDS_LIB"mstr_symbols"
SIZE"1B"
BOM_COST"MEM"
VOLTAGE"0"
ROOM"MEM_EFGH_DECOUPLING_CAPS"
BODY_TYPE"PLUMBING"
HDL_POWER"GND";
"A\NAC"2;
%"Q_RES"
"1","(-8500,2075)","2","pure_quanta","I188";
;
LOCATION"R313"
$SEC"1"
CDS_SEC"1"
VALUE"1K"
TOLERANCE"1%"
CDS_LIB"pure_quanta"
BOM_COST"MEM"
WATTAGE"1/16W"
MATERIAL"CHIP"
PACK_TYPE"0402LF"
ROOM""
PART_NUMBER"CS21002FB06";
"B"
$PN"2"159;
"A"
$PN"1"171;
%"VCC_CORE"
"1","(-8375,2400)","0","mstr_symbols","I189";
;
HDL_POWER"P3V3"
CDS_LIB"mstr_symbols"
VOLTAGE"3.3"
ROOM"PVCCINFAON_CPU0_CTRL";
"A"3;
%"Q_RES"
"2","(-8375,2225)","0","pure_quanta","I190";
;
LOCATION"R114"
$SEC"1"
CDS_SEC"1"
TOLERANCE"1%"
WATTAGE"1/16W"
MATERIAL"EMPTY"
PACK_TYPE"0402LF"
VALUE"1K"
CDS_LIB"pure_quanta"
BOM_COST"MEM"
ROOM""
PART_NUMBER"CS21002FB06";
"A"
$PN"1"3;
"B"
$PN"2"171;
%"TAP"
"1","(-3275,4350)","0","mstr_standard","I195";
;
CDS_LIB"mstr_standard"
BODY_TYPE"PLUMBING"
HDL_TAP"TRUE";
"B \NAC \NWC"7;
"S \NAC"
BN"8"152;
%"TAP"
"1","(-3275,4450)","0","mstr_standard","I196";
;
CDS_LIB"mstr_standard"
BODY_TYPE"PLUMBING"
HDL_TAP"TRUE";
"B \NAC \NWC"7;
"S \NAC"
BN"9"154;
%"TAP"
"1","(-3475,4500)","0","mstr_standard","I197";
;
CDS_LIB"mstr_standard"
BODY_TYPE"PLUMBING"
HDL_TAP"TRUE";
"B \NAC \NWC"4;
"S \NAC"
BN"9"157;
%"TAP"
"1","(-3475,4400)","0","mstr_standard","I198";
;
CDS_LIB"mstr_standard"
BODY_TYPE"PLUMBING"
HDL_TAP"TRUE";
"B \NAC \NWC"4;
"S \NAC"
BN"8"153;
%"TAP"
"1","(-3275,4250)","0","mstr_standard","I199";
;
CDS_LIB"mstr_standard"
BODY_TYPE"PLUMBING"
HDL_TAP"TRUE";
"B \NAC \NWC"7;
"S \NAC"
BN"7"118;
%"TAP"
"1","(-3275,4150)","0","mstr_standard","I200";
;
CDS_LIB"mstr_standard"
BODY_TYPE"PLUMBING"
HDL_TAP"TRUE";
"B \NAC \NWC"7;
"S \NAC"
BN"6"147;
%"TAP"
"1","(-3475,4300)","0","mstr_standard","I201";
;
CDS_LIB"mstr_standard"
BODY_TYPE"PLUMBING"
HDL_TAP"TRUE";
"B \NAC \NWC"4;
"S \NAC"
BN"7"150;
%"TAP"
"1","(-3475,4200)","0","mstr_standard","I202";
;
CDS_LIB"mstr_standard"
BODY_TYPE"PLUMBING"
HDL_TAP"TRUE";
"B \NAC \NWC"4;
"S \NAC"
BN"6"119;
%"TAP"
"1","(-3475,4100)","0","mstr_standard","I203";
;
CDS_LIB"mstr_standard"
BODY_TYPE"PLUMBING"
HDL_TAP"TRUE";
"B \NAC \NWC"4;
"S \NAC"
BN"5"144;
%"TAP"
"1","(-3275,4050)","0","mstr_standard","I204";
;
CDS_LIB"mstr_standard"
BODY_TYPE"PLUMBING"
HDL_TAP"TRUE";
"B \NAC \NWC"7;
"S \NAC"
BN"5"143;
%"TAP"
"1","(-3275,3850)","0","mstr_standard","I205";
;
CDS_LIB"mstr_standard"
BODY_TYPE"PLUMBING"
HDL_TAP"TRUE";
"B \NAC \NWC"7;
"S \NAC"
BN"3"135;
%"TAP"
"1","(-3275,3950)","0","mstr_standard","I206";
;
CDS_LIB"mstr_standard"
BODY_TYPE"PLUMBING"
HDL_TAP"TRUE";
"B \NAC \NWC"7;
"S \NAC"
BN"4"139;
%"TAP"
"1","(-3475,4000)","0","mstr_standard","I207";
;
CDS_LIB"mstr_standard"
BODY_TYPE"PLUMBING"
HDL_TAP"TRUE";
"B \NAC \NWC"4;
"S \NAC"
BN"4"140;
%"TAP"
"1","(-3475,3900)","0","mstr_standard","I208";
;
CDS_LIB"mstr_standard"
BODY_TYPE"PLUMBING"
HDL_TAP"TRUE";
"B \NAC \NWC"4;
"S \NAC"
BN"3"136;
%"TAP"
"1","(-3275,3750)","0","mstr_standard","I209";
;
CDS_LIB"mstr_standard"
BODY_TYPE"PLUMBING"
HDL_TAP"TRUE";
"B \NAC \NWC"7;
"S \NAC"
BN"2"131;
%"TAP"
"1","(-3275,3650)","0","mstr_standard","I210";
;
CDS_LIB"mstr_standard"
BODY_TYPE"PLUMBING"
HDL_TAP"TRUE";
"B \NAC \NWC"7;
"S \NAC"
BN"1"127;
%"TAP"
"1","(-3475,3800)","0","mstr_standard","I211";
;
CDS_LIB"mstr_standard"
BODY_TYPE"PLUMBING"
HDL_TAP"TRUE";
"B \NAC \NWC"4;
"S \NAC"
BN"2"132;
%"TAP"
"1","(-3475,3700)","0","mstr_standard","I212";
;
CDS_LIB"mstr_standard"
BODY_TYPE"PLUMBING"
HDL_TAP"TRUE";
"B \NAC \NWC"4;
"S \NAC"
BN"1"128;
%"TAP"
"1","(-3475,3600)","0","mstr_standard","I213";
;
CDS_LIB"mstr_standard"
BODY_TYPE"PLUMBING"
HDL_TAP"TRUE";
"B \NAC \NWC"4;
"S \NAC"
BN"0"124;
%"TAP"
"1","(-3275,3550)","0","mstr_standard","I214";
;
CDS_LIB"mstr_standard"
BODY_TYPE"PLUMBING"
HDL_TAP"TRUE";
"B \NAC \NWC"7;
"S \NAC"
BN"0"123;
%"TAP"
"1","(-3275,3400)","0","mstr_standard","I215";
;
CDS_LIB"mstr_standard"
BODY_TYPE"PLUMBING"
HDL_TAP"TRUE";
"B \NAC \NWC"6;
"S \NAC"
BN"9"155;
%"TAP"
"1","(-3475,3450)","0","mstr_standard","I216";
;
CDS_LIB"mstr_standard"
BODY_TYPE"PLUMBING"
HDL_TAP"TRUE";
"B \NAC \NWC"5;
"S \NAC"
BN"9"156;
%"TAP"
"1","(-3475,3350)","0","mstr_standard","I217";
;
CDS_LIB"mstr_standard"
BODY_TYPE"PLUMBING"
HDL_TAP"TRUE";
"B \NAC \NWC"5;
"S \NAC"
BN"8"120;
%"TAP"
"1","(-3275,3200)","0","mstr_standard","I218";
;
CDS_LIB"mstr_standard"
BODY_TYPE"PLUMBING"
HDL_TAP"TRUE";
"B \NAC \NWC"6;
"S \NAC"
BN"7"151;
%"TAP"
"1","(-3275,3300)","0","mstr_standard","I219";
;
CDS_LIB"mstr_standard"
BODY_TYPE"PLUMBING"
HDL_TAP"TRUE";
"B \NAC \NWC"6;
"S \NAC"
BN"8"121;
%"SCONN288_DDR506112002KQ"
"1","(-6850,3575)","0","pure_quanta","I22";
;
LOCATION"J99"
$SEC"1"
CDS_SEC"1"
PART_TYPE"SMLF"
MATERIAL"IO"
VALUE"SCONN288_DDR506112002KQ"
CDS_LMAN_SYM_OUTLINE"-450,1900,450,-1850"
NEEDS_NO_SIZE"TRUE"
CDS_LIB"pure_quanta"
PART_NUMBER"DFHST8FS479";
"PWR_GOOD||FAIL_N"
$PN"147"171;
"DQ31_A"
$PN"194"15;
"CB7_A"
$PN"205"16;
"CB4_A"
$PN"58"17;
"CB1_A"
$PN"53"18;
"CB7_B"
$PN"236"19;
"ALERT_N \B"
$PN"62"161;
"CA0_A"
$PN"66"20;
"CA0_B"
$PN"76"21;
"CA1_A"
$PN"211"22;
"CA1_B"
$PN"221"23;
"CA2_A"
$PN"68"24;
"CA2_B"
$PN"78"25;
"CA3_A"
$PN"213"26;
"CA3_B"
$PN"223"27;
"CA4_A"
$PN"70"28;
"CA4_B"
$PN"80"29;
"CA5_A"
$PN"215"30;
"CA5_B"
$PN"225"31;
"CA6_A"
$PN"72"32;
"CA6_B"
$PN"82"33;
"CB6_A"
$PN"203"34;
"CB5_A"
$PN"60"35;
"CB3_A"
$PN"198"36;
"CB2_A"
$PN"196"37;
"CB0_A"
$PN"51"38;
"CB6_B"
$PN"234"39;
"CB5_B"
$PN"91"40;
"CB4_B"
$PN"89"41;
"CB3_B"
$PN"243"14;
"CB2_B"
$PN"241"42;
"CB1_B"
$PN"98"43;
"CB0_B"
$PN"96"44;
"CK_C \B"
$PN"218"45;
"CK_T"
$PN"217"46;
"CS0_A_N"
$PN"64"47;
"CS0_B_N"
$PN"84"48;
"CS1_A_N"
$PN"209"49;
"CS1_B_N"
$PN"229"50;
"DQ30_A"
$PN"192"51;
"DQ29_A"
$PN"49"52;
"DQ28_A"
$PN"47"53;
"DQ27_A"
$PN"187"54;
"DQ26_A"
$PN"185"55;
"DQ25_A"
$PN"42"56;
"DQ24_A"
$PN"40"57;
"DQ23_A"
$PN"183"58;
"DQ22_A"
$PN"181"59;
"DQ21_A"
$PN"38"60;
"DQ20_A"
$PN"36"61;
"DQ19_A"
$PN"176"62;
"DQ18_A"
$PN"174"63;
"DQ17_A"
$PN"31"64;
"DQ16_A"
$PN"29"65;
"DQ15_A"
$PN"172"66;
"DQ14_A"
$PN"170"67;
"DQ13_A"
$PN"27"68;
"DQ12_A"
$PN"25"69;
"DQ11_A"
$PN"165"70;
"DQ10_A"
$PN"163"71;
"DQ9_A"
$PN"20"72;
"DQ8_A"
$PN"18"73;
"DQ7_A"
$PN"161"74;
"DQ6_A"
$PN"159"75;
"DQ5_A"
$PN"16"76;
"DQ4_A"
$PN"14"77;
"DQ3_A"
$PN"154"78;
"DQ2_A"
$PN"152"79;
"DQ1_A"
$PN"9"80;
"DQ0_A"
$PN"7"81;
"DQ31_B"
$PN"287"82;
"DQ30_B"
$PN"285"83;
"DQ29_B"
$PN"142"84;
"DQ28_B"
$PN"140"85;
"DQ27_B"
$PN"280"86;
"DQ26_B"
$PN"278"87;
"DQ25_B"
$PN"135"88;
"DQ24_B"
$PN"133"89;
"DQ23_B"
$PN"276"90;
"DQ22_B"
$PN"274"91;
"DQ21_B"
$PN"131"92;
"DQ20_B"
$PN"129"93;
"DQ19_B"
$PN"269"94;
"DQ18_B"
$PN"267"95;
"DQ17_B"
$PN"124"96;
"DQ16_B"
$PN"122"97;
"DQ15_B"
$PN"265"98;
"DQ14_B"
$PN"263"99;
"DQ13_B"
$PN"120"100;
"DQ12_B"
$PN"118"101;
"DQ11_B"
$PN"258"102;
"DQ10_B"
$PN"256"103;
"DQ9_B"
$PN"113"104;
"DQ8_B"
$PN"111"105;
"DQ7_B"
$PN"254"106;
"DQ6_B"
$PN"252"107;
"DQ5_B"
$PN"109"108;
"DQ4_B"
$PN"107"109;
"DQ3_B"
$PN"247"110;
"DQ2_B"
$PN"245"111;
"DQ1_B"
$PN"102"112;
"DQ0_B"
$PN"100"113;
"HAS"
$PN"148"162;
"HSCL"
$PN"4"168;
"HSDA"
$PN"5"169;
"LBD||RSP_A_N"
$PN"86"114;
"LBS||RSP_B_N"
$PN"87"115;
"PAR_A"
$PN"74"116;
"PAR_B"
$PN"227"117;
"RESET_N \B"
$PN"207"160;
"RFU6"
$PN"232"0;
"RFU5"
$PN"231"0;
"RFU4"
$PN"220"0;
"RFU3"
$PN"150"0;
"RFU2"
$PN"149"0;
"RFU1"
$PN"144"0;
"RFU0"
$PN"2"0;
"VIN_MGMT"
$PN"3"163;
%"TAP"
"1","(-3275,3100)","0","mstr_standard","I220";
;
CDS_LIB"mstr_standard"
BODY_TYPE"PLUMBING"
HDL_TAP"TRUE";
"B \NAC \NWC"6;
"S \NAC"
BN"6"148;
%"TAP"
"1","(-3475,3250)","0","mstr_standard","I221";
;
CDS_LIB"mstr_standard"
BODY_TYPE"PLUMBING"
HDL_TAP"TRUE";
"B \NAC \NWC"5;
"S \NAC"
BN"7"122;
%"TAP"
"1","(-3475,3150)","0","mstr_standard","I222";
;
CDS_LIB"mstr_standard"
BODY_TYPE"PLUMBING"
HDL_TAP"TRUE";
"B \NAC \NWC"5;
"S \NAC"
BN"6"149;
%"TAP"
"1","(-3275,3000)","0","mstr_standard","I223";
;
CDS_LIB"mstr_standard"
BODY_TYPE"PLUMBING"
HDL_TAP"TRUE";
"B \NAC \NWC"6;
"S \NAC"
BN"5"145;
%"TAP"
"1","(-3275,2900)","0","mstr_standard","I224";
;
CDS_LIB"mstr_standard"
BODY_TYPE"PLUMBING"
HDL_TAP"TRUE";
"B \NAC \NWC"6;
"S \NAC"
BN"4"141;
%"TAP"
"1","(-3475,2950)","0","mstr_standard","I225";
;
CDS_LIB"mstr_standard"
BODY_TYPE"PLUMBING"
HDL_TAP"TRUE";
"B \NAC \NWC"5;
"S \NAC"
BN"4"142;
%"TAP"
"1","(-3475,3050)","0","mstr_standard","I226";
;
CDS_LIB"mstr_standard"
BODY_TYPE"PLUMBING"
HDL_TAP"TRUE";
"B \NAC \NWC"5;
"S \NAC"
BN"5"146;
%"TAP"
"1","(-3475,2850)","0","mstr_standard","I227";
;
CDS_LIB"mstr_standard"
BODY_TYPE"PLUMBING"
HDL_TAP"TRUE";
"B \NAC \NWC"5;
"S \NAC"
BN"3"138;
%"TAP"
"1","(-3275,2700)","0","mstr_standard","I228";
;
CDS_LIB"mstr_standard"
BODY_TYPE"PLUMBING"
HDL_TAP"TRUE";
"B \NAC \NWC"6;
"S \NAC"
BN"2"133;
%"TAP"
"1","(-3275,2800)","0","mstr_standard","I229";
;
CDS_LIB"mstr_standard"
BODY_TYPE"PLUMBING"
HDL_TAP"TRUE";
"B \NAC \NWC"6;
"S \NAC"
BN"3"137;
%"TAP"
"1","(-7700,3125)","2","mstr_standard","I23";
;
CDS_LIB"mstr_standard"
BODY_TYPE"PLUMBING"
HDL_TAP"TRUE";
"B \NAC \NWC"10;
"S \NAC"
BN"0"44;
%"TAP"
"1","(-3275,2600)","0","mstr_standard","I230";
;
CDS_LIB"mstr_standard"
BODY_TYPE"PLUMBING"
HDL_TAP"TRUE";
"B \NAC \NWC"6;
"S \NAC"
BN"1"129;
%"TAP"
"1","(-3475,2750)","0","mstr_standard","I231";
;
CDS_LIB"mstr_standard"
BODY_TYPE"PLUMBING"
HDL_TAP"TRUE";
"B \NAC \NWC"5;
"S \NAC"
BN"2"134;
%"TAP"
"1","(-3475,2650)","0","mstr_standard","I232";
;
CDS_LIB"mstr_standard"
BODY_TYPE"PLUMBING"
HDL_TAP"TRUE";
"B \NAC \NWC"5;
"S \NAC"
BN"1"130;
%"TAP"
"1","(-3475,2550)","0","mstr_standard","I233";
;
CDS_LIB"mstr_standard"
BODY_TYPE"PLUMBING"
HDL_TAP"TRUE";
"B \NAC \NWC"5;
"S \NAC"
BN"0"126;
%"TAP"
"1","(-3275,2500)","0","mstr_standard","I234";
;
CDS_LIB"mstr_standard"
BODY_TYPE"PLUMBING"
HDL_TAP"TRUE";
"B \NAC \NWC"6;
"S \NAC"
BN"0"125;
%"SCONN288_DDR506112002KQ"
"2","(-4425,3500)","0","pure_quanta","I235";
;
LOCATION"J99"
$SEC"2"
CDS_SEC"2"
MATERIAL"IO"
VALUE"SCONN288_DDR506112002KQ"
PART_TYPE"SMLF"
CDS_LMAN_SYM_OUTLINE"-600,1150,600,-1150"
NEEDS_NO_SIZE"TRUE"
CDS_LIB"pure_quanta"
PART_NUMBER"DFHST8FS479";
"DQS7_A_C||TDQS7_A_C \B"
$PN"178"118;
"DQS6_A_T||TDQS6_A_T"
$PN"168"119;
"DQS8_B_T||TDQS8_B_T"
$PN"283"120;
"DQS8_B_C||TDQS8_B_C \B"
$PN"282"121;
"DQS7_B_T||TDQS7_B_T"
$PN"272"122;
"DQS0_A_C \B"
$PN"12"123;
"DQS0_A_T"
$PN"11"124;
"DQS0_B_C \B"
$PN"105"125;
"DQS0_B_T"
$PN"104"126;
"DQS1_A_C \B"
$PN"23"127;
"DQS1_A_T"
$PN"22"128;
"DQS1_B_C \B"
$PN"116"129;
"DQS1_B_T"
$PN"115"130;
"DQS2_A_C \B"
$PN"34"131;
"DQS2_A_T"
$PN"33"132;
"DQS2_B_C \B"
$PN"127"133;
"DQS2_B_T"
$PN"126"134;
"DQS3_A_C \B"
$PN"45"135;
"DQS3_A_T"
$PN"44"136;
"DQS3_B_C \B"
$PN"138"137;
"DQS3_B_T"
$PN"137"138;
"DQS4_A_C \B"
$PN"56"139;
"DQS4_A_T"
$PN"55"140;
"DQS4_B_C \B"
$PN"238"141;
"DQS4_B_T"
$PN"239"142;
"DQS5_A_C||TDQS5_A_C||DQS5_A_T||TDQS5_A_T \B"
$PN"156"143;
"DQS5_A_T||TDQS5_A_T"
$PN"157"144;
"DQS5_B_C||TDQS5_B_C \B"
$PN"249"145;
"DQS5_B_T||TDQS5_B_T"
$PN"250"146;
"DQS6_A_C||TDQS6_A_C||DQS6_A_T||TDQS6_A_T \B"
$PN"167"147;
"DQS6_B_C||TDQS6_B_C \B"
$PN"260"148;
"DQS6_B_T||TDQS6_B_T"
$PN"261"149;
"DQS7_A_T||TDQS7_A_T"
$PN"179"150;
"DQS7_B_C||TDQS7_B_C \B"
$PN"271"151;
"DQS8_A_C||TDQS8_A_C \B"
$PN"189"152;
"DQS8_A_T||TDQS8_A_T"
$PN"190"153;
"DQS9_A_C||TDQS9_A_C \B"
$PN"200"154;
"DQS9_A_T||TDQS9_A_T"
$PN"201"157;
"DQS9_B_C||TDQS9_B_C \B"
$PN"94"155;
"DQS9_B_T||TDQS9_B_T||DBI4_B_N"
$PN"93"156;
%"GND"
"1","(-2850,5475)","0","pure_quanta_power","I236";
;
SIZE"1B"
BOM_COST"MEM"
CDS_LIB"pure_quanta_power"
ROOM"MEM_EFGH_DECOUPLING_CAPS"
HDL_POWER"GND";
"A<SIZE-1..0>\NAC"165;
%"Q_CAP"
"1","(-2850,5825)","2","pure_quanta","I237";
;
LOCATION"C546"
$SEC"1"
CDS_SEC"1"
PACK_TYPE"C0805"
VOLTAGE"25V"
VALUE"10UF"
TOLERANCE"10%"
MATERIAL"X6S"
BOM_COST"MEM"
CDS_LIB"pure_quanta"
ROOM""
PART_NUMBER"CH6104KEA00";
"B"
$PN"2"165;
"A"
$PN"1"164;
%"Q_CAP"
"1","(-2275,5825)","2","pure_quanta","I238";
;
LOCATION"C547"
$SEC"1"
CDS_SEC"1"
PACK_TYPE"C0805"
VOLTAGE"25V"
VALUE"10UF"
TOLERANCE"10%"
MATERIAL"X6S"
BOM_COST"MEM"
CDS_LIB"pure_quanta"
ROOM""
PART_NUMBER"CH6104KEA00";
"B"
$PN"2"165;
"A"
$PN"1"164;
%"UNIVERSAL_POWER"
"1","(-2850,6150)","0","pure_quanta_power","I239";
;
HDL_POWER"P12V_MEM_CPU1"
CDS_LIB"pure_quanta_power";
"A"164;
%"TAP"
"1","(-7700,3175)","2","mstr_standard","I24";
;
CDS_LIB"mstr_standard"
BODY_TYPE"PLUMBING"
HDL_TAP"TRUE";
"B \NAC \NWC"10;
"S \NAC"
BN"1"43;
%"Q_RES"
"1","(-7750,2550)","0","pure_quanta","I241";
;
LOCATION"R1590"
$SEC"1"
CDS_SEC"1"
VALUE"49.9"
CDS_LIB"pure_quanta"
TOLERANCE"1%"
WATTAGE"1/16W"
PACK_TYPE"0402LF"
MATERIAL"CHIP"
PART_NUMBER"CS04992FB07";
"B"
$PN"2"168;
"A"
$PN"1"172;
%"Q_RES"
"1","(-8125,2775)","0","pure_quanta","I242";
;
LOCATION"R1710"
$SEC"1"
CDS_SEC"1"
VALUE"10"
PACK_TYPE"0402LF"
MATERIAL"CHIP"
CDS_LIB"pure_quanta"
WATTAGE"1/16W"
TOLERANCE"1%"
PART_NUMBER"CS01002FB07";
"B"
$PN"2"169;
"A"
$PN"1"170;
%"TAP"
"1","(-7700,3225)","2","mstr_standard","I25";
;
CDS_LIB"mstr_standard"
BODY_TYPE"PLUMBING"
HDL_TAP"TRUE";
"B \NAC \NWC"10;
"S \NAC"
BN"2"42;
%"TAP"
"1","(-7700,3325)","2","mstr_standard","I26";
;
CDS_LIB"mstr_standard"
BODY_TYPE"PLUMBING"
HDL_TAP"TRUE";
"B \NAC \NWC"10;
"S \NAC"
BN"4"41;
%"TAP"
"1","(-7700,3375)","2","mstr_standard","I27";
;
CDS_LIB"mstr_standard"
BODY_TYPE"PLUMBING"
HDL_TAP"TRUE";
"B \NAC \NWC"10;
"S \NAC"
BN"5"40;
%"TAP"
"1","(-7700,3275)","2","mstr_standard","I28";
;
CDS_LIB"mstr_standard"
BODY_TYPE"PLUMBING"
HDL_TAP"TRUE";
"B \NAC \NWC"10;
"S \NAC"
BN"3"14;
%"TAP"
"1","(-7700,3575)","2","mstr_standard","I29";
;
CDS_LIB"mstr_standard"
BODY_TYPE"PLUMBING"
HDL_TAP"TRUE";
"B \NAC \NWC"11;
"S \NAC"
BN"0"38;
%"TAP"
"1","(-7700,3625)","2","mstr_standard","I30";
;
CDS_LIB"mstr_standard"
BODY_TYPE"PLUMBING"
HDL_TAP"TRUE";
"B \NAC \NWC"11;
"S \NAC"
BN"1"18;
%"TAP"
"1","(-7700,3425)","2","mstr_standard","I31";
;
CDS_LIB"mstr_standard"
BODY_TYPE"PLUMBING"
HDL_TAP"TRUE";
"B \NAC \NWC"10;
"S \NAC"
BN"6"39;
%"TAP"
"1","(-7700,3475)","2","mstr_standard","I32";
;
CDS_LIB"mstr_standard"
BODY_TYPE"PLUMBING"
HDL_TAP"TRUE";
"B \NAC \NWC"10;
"S \NAC"
BN"7"19;
%"TAP"
"1","(-6000,2125)","0","mstr_standard","I33";
;
CDS_LIB"mstr_standard"
BODY_TYPE"PLUMBING"
HDL_TAP"TRUE";
"B \NAC \NWC"8;
"S \NAC"
BN"0"113;
%"TAP"
"1","(-6000,2175)","0","mstr_standard","I34";
;
CDS_LIB"mstr_standard"
BODY_TYPE"PLUMBING"
HDL_TAP"TRUE";
"B \NAC \NWC"8;
"S \NAC"
BN"1"112;
%"TAP"
"1","(-6000,2225)","0","mstr_standard","I35";
;
CDS_LIB"mstr_standard"
BODY_TYPE"PLUMBING"
HDL_TAP"TRUE";
"B \NAC \NWC"8;
"S \NAC"
BN"2"111;
%"TAP"
"1","(-6000,2275)","0","mstr_standard","I36";
;
CDS_LIB"mstr_standard"
BODY_TYPE"PLUMBING"
HDL_TAP"TRUE";
"B \NAC \NWC"8;
"S \NAC"
BN"3"110;
%"TAP"
"1","(-6000,2325)","0","mstr_standard","I37";
;
CDS_LIB"mstr_standard"
BODY_TYPE"PLUMBING"
HDL_TAP"TRUE";
"B \NAC \NWC"8;
"S \NAC"
BN"4"109;
%"TAP"
"1","(-6000,2375)","0","mstr_standard","I38";
;
CDS_LIB"mstr_standard"
BODY_TYPE"PLUMBING"
HDL_TAP"TRUE";
"B \NAC \NWC"8;
"S \NAC"
BN"5"108;
%"TAP"
"1","(-6000,2425)","0","mstr_standard","I39";
;
CDS_LIB"mstr_standard"
BODY_TYPE"PLUMBING"
HDL_TAP"TRUE";
"B \NAC \NWC"8;
"S \NAC"
BN"6"107;
%"TAP"
"1","(-6000,2475)","0","mstr_standard","I40";
;
CDS_LIB"mstr_standard"
BODY_TYPE"PLUMBING"
HDL_TAP"TRUE";
"B \NAC \NWC"8;
"S \NAC"
BN"7"106;
%"TAP"
"1","(-6000,2525)","0","mstr_standard","I41";
;
CDS_LIB"mstr_standard"
BODY_TYPE"PLUMBING"
HDL_TAP"TRUE";
"B \NAC \NWC"8;
"S \NAC"
BN"8"105;
%"TAP"
"1","(-6000,2625)","0","mstr_standard","I42";
;
CDS_LIB"mstr_standard"
BODY_TYPE"PLUMBING"
HDL_TAP"TRUE";
"B \NAC \NWC"8;
"S \NAC"
BN"10"103;
%"TAP"
"1","(-6000,2575)","0","mstr_standard","I43";
;
CDS_LIB"mstr_standard"
BODY_TYPE"PLUMBING"
HDL_TAP"TRUE";
"B \NAC \NWC"8;
"S \NAC"
BN"9"104;
%"TAP"
"1","(-6000,2675)","0","mstr_standard","I44";
;
CDS_LIB"mstr_standard"
BODY_TYPE"PLUMBING"
HDL_TAP"TRUE";
"B \NAC \NWC"8;
"S \NAC"
BN"11"102;
%"TAP"
"1","(-6000,2725)","0","mstr_standard","I45";
;
CDS_LIB"mstr_standard"
BODY_TYPE"PLUMBING"
HDL_TAP"TRUE";
"B \NAC \NWC"8;
"S \NAC"
BN"12"101;
%"TAP"
"1","(-6000,2775)","0","mstr_standard","I46";
;
CDS_LIB"mstr_standard"
BODY_TYPE"PLUMBING"
HDL_TAP"TRUE";
"B \NAC \NWC"8;
"S \NAC"
BN"13"100;
%"TAP"
"1","(-6000,2825)","0","mstr_standard","I47";
;
CDS_LIB"mstr_standard"
BODY_TYPE"PLUMBING"
HDL_TAP"TRUE";
"B \NAC \NWC"8;
"S \NAC"
BN"14"99;
%"TAP"
"1","(-6000,2875)","0","mstr_standard","I48";
;
CDS_LIB"mstr_standard"
BODY_TYPE"PLUMBING"
HDL_TAP"TRUE";
"B \NAC \NWC"8;
"S \NAC"
BN"15"98;
%"TAP"
"1","(-6000,2925)","0","mstr_standard","I49";
;
CDS_LIB"mstr_standard"
BODY_TYPE"PLUMBING"
HDL_TAP"TRUE";
"B \NAC \NWC"8;
"S \NAC"
BN"16"97;
%"TAP"
"1","(-6000,2975)","0","mstr_standard","I50";
;
CDS_LIB"mstr_standard"
BODY_TYPE"PLUMBING"
HDL_TAP"TRUE";
"B \NAC \NWC"8;
"S \NAC"
BN"17"96;
%"TAP"
"1","(-6000,3025)","0","mstr_standard","I51";
;
CDS_LIB"mstr_standard"
BODY_TYPE"PLUMBING"
HDL_TAP"TRUE";
"B \NAC \NWC"8;
"S \NAC"
BN"18"95;
%"TAP"
"1","(-6000,3075)","0","mstr_standard","I52";
;
CDS_LIB"mstr_standard"
BODY_TYPE"PLUMBING"
HDL_TAP"TRUE";
"B \NAC \NWC"8;
"S \NAC"
BN"19"94;
%"TAP"
"1","(-6000,3125)","0","mstr_standard","I53";
;
CDS_LIB"mstr_standard"
BODY_TYPE"PLUMBING"
HDL_TAP"TRUE";
"B \NAC \NWC"8;
"S \NAC"
BN"20"93;
%"TAP"
"1","(-6000,3175)","0","mstr_standard","I54";
;
CDS_LIB"mstr_standard"
BODY_TYPE"PLUMBING"
HDL_TAP"TRUE";
"B \NAC \NWC"8;
"S \NAC"
BN"21"92;
%"TAP"
"1","(-6000,3225)","0","mstr_standard","I55";
;
CDS_LIB"mstr_standard"
BODY_TYPE"PLUMBING"
HDL_TAP"TRUE";
"B \NAC \NWC"8;
"S \NAC"
BN"22"91;
%"TAP"
"1","(-6000,3275)","0","mstr_standard","I56";
;
CDS_LIB"mstr_standard"
BODY_TYPE"PLUMBING"
HDL_TAP"TRUE";
"B \NAC \NWC"8;
"S \NAC"
BN"23"90;
%"TAP"
"1","(-6000,3325)","0","mstr_standard","I57";
;
CDS_LIB"mstr_standard"
BODY_TYPE"PLUMBING"
HDL_TAP"TRUE";
"B \NAC \NWC"8;
"S \NAC"
BN"24"89;
%"TAP"
"1","(-6000,3375)","0","mstr_standard","I58";
;
CDS_LIB"mstr_standard"
BODY_TYPE"PLUMBING"
HDL_TAP"TRUE";
"B \NAC \NWC"8;
"S \NAC"
BN"25"88;
%"TAP"
"1","(-6000,3425)","0","mstr_standard","I59";
;
CDS_LIB"mstr_standard"
BODY_TYPE"PLUMBING"
HDL_TAP"TRUE";
"B \NAC \NWC"8;
"S \NAC"
BN"26"87;
%"TAP"
"1","(-6000,3475)","0","mstr_standard","I60";
;
CDS_LIB"mstr_standard"
BODY_TYPE"PLUMBING"
HDL_TAP"TRUE";
"B \NAC \NWC"8;
"S \NAC"
BN"27"86;
%"TAP"
"1","(-6000,3525)","0","mstr_standard","I61";
;
CDS_LIB"mstr_standard"
BODY_TYPE"PLUMBING"
HDL_TAP"TRUE";
"B \NAC \NWC"8;
"S \NAC"
BN"28"85;
%"TAP"
"1","(-6000,3575)","0","mstr_standard","I62";
;
CDS_LIB"mstr_standard"
BODY_TYPE"PLUMBING"
HDL_TAP"TRUE";
"B \NAC \NWC"8;
"S \NAC"
BN"29"84;
%"TAP"
"1","(-6000,3625)","0","mstr_standard","I63";
;
CDS_LIB"mstr_standard"
BODY_TYPE"PLUMBING"
HDL_TAP"TRUE";
"B \NAC \NWC"8;
"S \NAC"
BN"30"83;
%"VCC_CORE"
"1","(-8575,3350)","0","mstr_symbols","I7";
;
HDL_POWER"P3V3_AUX"
CDS_LIB"mstr_symbols"
VOLTAGE"3.3"
ROOM"PVCCINFAON_CPU1_CTRL";
"A"163;
%"TAP"
"1","(-7700,3675)","2","mstr_standard","I71";
;
CDS_LIB"mstr_standard"
BODY_TYPE"PLUMBING"
HDL_TAP"TRUE";
"B \NAC \NWC"11;
"S \NAC"
BN"2"37;
%"TAP"
"1","(-7700,3725)","2","mstr_standard","I72";
;
CDS_LIB"mstr_standard"
BODY_TYPE"PLUMBING"
HDL_TAP"TRUE";
"B \NAC \NWC"11;
"S \NAC"
BN"3"36;
%"TAP"
"1","(-7700,3825)","2","mstr_standard","I73";
;
CDS_LIB"mstr_standard"
BODY_TYPE"PLUMBING"
HDL_TAP"TRUE";
"B \NAC \NWC"11;
"S \NAC"
BN"5"35;
%"TAP"
"1","(-7700,3875)","2","mstr_standard","I74";
;
CDS_LIB"mstr_standard"
BODY_TYPE"PLUMBING"
HDL_TAP"TRUE";
"B \NAC \NWC"11;
"S \NAC"
BN"6"34;
%"TAP"
"1","(-7700,3775)","2","mstr_standard","I75";
;
CDS_LIB"mstr_standard"
BODY_TYPE"PLUMBING"
HDL_TAP"TRUE";
"B \NAC \NWC"11;
"S \NAC"
BN"4"17;
%"TAP"
"1","(-7700,3925)","2","mstr_standard","I76";
;
CDS_LIB"mstr_standard"
BODY_TYPE"PLUMBING"
HDL_TAP"TRUE";
"B \NAC \NWC"11;
"S \NAC"
BN"7"16;
%"TAP"
"1","(-7700,4625)","2","mstr_standard","I77";
;
CDS_LIB"mstr_standard"
BODY_TYPE"PLUMBING"
HDL_TAP"TRUE";
"B \NAC \NWC"12;
"S \NAC"
BN"0"21;
%"TAP"
"1","(-7700,4675)","2","mstr_standard","I78";
;
CDS_LIB"mstr_standard"
BODY_TYPE"PLUMBING"
HDL_TAP"TRUE";
"B \NAC \NWC"12;
"S \NAC"
BN"1"23;
%"TAP"
"1","(-7700,4725)","2","mstr_standard","I79";
;
CDS_LIB"mstr_standard"
BODY_TYPE"PLUMBING"
HDL_TAP"TRUE";
"B \NAC \NWC"12;
"S \NAC"
BN"2"25;
%"TAP"
"1","(-7700,4775)","2","mstr_standard","I80";
;
CDS_LIB"mstr_standard"
BODY_TYPE"PLUMBING"
HDL_TAP"TRUE";
"B \NAC \NWC"12;
"S \NAC"
BN"3"27;
%"TAP"
"1","(-7700,4825)","2","mstr_standard","I81";
;
CDS_LIB"mstr_standard"
BODY_TYPE"PLUMBING"
HDL_TAP"TRUE";
"B \NAC \NWC"12;
"S \NAC"
BN"4"29;
%"TAP"
"1","(-7700,4925)","2","mstr_standard","I82";
;
CDS_LIB"mstr_standard"
BODY_TYPE"PLUMBING"
HDL_TAP"TRUE";
"B \NAC \NWC"12;
"S \NAC"
BN"6"33;
%"TAP"
"1","(-7700,4875)","2","mstr_standard","I83";
;
CDS_LIB"mstr_standard"
BODY_TYPE"PLUMBING"
HDL_TAP"TRUE";
"B \NAC \NWC"12;
"S \NAC"
BN"5"31;
%"TAP"
"1","(-7700,5075)","2","mstr_standard","I84";
;
CDS_LIB"mstr_standard"
BODY_TYPE"PLUMBING"
HDL_TAP"TRUE";
"B \NAC \NWC"13;
"S \NAC"
BN"1"22;
%"TAP"
"1","(-7700,5125)","2","mstr_standard","I85";
;
CDS_LIB"mstr_standard"
BODY_TYPE"PLUMBING"
HDL_TAP"TRUE";
"B \NAC \NWC"13;
"S \NAC"
BN"2"24;
%"TAP"
"1","(-7700,5175)","2","mstr_standard","I86";
;
CDS_LIB"mstr_standard"
BODY_TYPE"PLUMBING"
HDL_TAP"TRUE";
"B \NAC \NWC"13;
"S \NAC"
BN"3"26;
%"TAP"
"1","(-7700,5025)","2","mstr_standard","I87";
;
CDS_LIB"mstr_standard"
BODY_TYPE"PLUMBING"
HDL_TAP"TRUE";
"B \NAC \NWC"13;
"S \NAC"
BN"0"20;
%"TAP"
"1","(-7700,5275)","2","mstr_standard","I88";
;
CDS_LIB"mstr_standard"
BODY_TYPE"PLUMBING"
HDL_TAP"TRUE";
"B \NAC \NWC"13;
"S \NAC"
BN"5"30;
%"TAP"
"1","(-7700,5325)","2","mstr_standard","I89";
;
CDS_LIB"mstr_standard"
BODY_TYPE"PLUMBING"
HDL_TAP"TRUE";
"B \NAC \NWC"13;
"S \NAC"
BN"6"32;
%"TAP"
"1","(-7700,5225)","2","mstr_standard","I90";
;
CDS_LIB"mstr_standard"
BODY_TYPE"PLUMBING"
HDL_TAP"TRUE";
"B \NAC \NWC"13;
"S \NAC"
BN"4"28;
%"TAP"
"1","(-6000,3675)","0","mstr_standard","I91";
;
CDS_LIB"mstr_standard"
BODY_TYPE"PLUMBING"
HDL_TAP"TRUE";
"B \NAC \NWC"8;
"S \NAC"
BN"31"82;
%"TAP"
"1","(-6000,3775)","0","mstr_standard","I92";
;
CDS_LIB"mstr_standard"
BODY_TYPE"PLUMBING"
HDL_TAP"TRUE";
"B \NAC \NWC"9;
"S \NAC"
BN"0"81;
%"TAP"
"1","(-6000,3825)","0","mstr_standard","I93";
;
CDS_LIB"mstr_standard"
BODY_TYPE"PLUMBING"
HDL_TAP"TRUE";
"B \NAC \NWC"9;
"S \NAC"
BN"1"80;
%"TAP"
"1","(-6000,3875)","0","mstr_standard","I94";
;
CDS_LIB"mstr_standard"
BODY_TYPE"PLUMBING"
HDL_TAP"TRUE";
"B \NAC \NWC"9;
"S \NAC"
BN"2"79;
%"TAP"
"1","(-6000,3925)","0","mstr_standard","I95";
;
CDS_LIB"mstr_standard"
BODY_TYPE"PLUMBING"
HDL_TAP"TRUE";
"B \NAC \NWC"9;
"S \NAC"
BN"3"78;
%"TAP"
"1","(-6000,3975)","0","mstr_standard","I96";
;
CDS_LIB"mstr_standard"
BODY_TYPE"PLUMBING"
HDL_TAP"TRUE";
"B \NAC \NWC"9;
"S \NAC"
BN"4"77;
%"TAP"
"1","(-6000,4025)","0","mstr_standard","I97";
;
CDS_LIB"mstr_standard"
BODY_TYPE"PLUMBING"
HDL_TAP"TRUE";
"B \NAC \NWC"9;
"S \NAC"
BN"5"76;
%"TAP"
"1","(-6000,4075)","0","mstr_standard","I98";
;
CDS_LIB"mstr_standard"
BODY_TYPE"PLUMBING"
HDL_TAP"TRUE";
"B \NAC \NWC"9;
"S \NAC"
BN"6"75;
%"TAP"
"1","(-6000,4125)","0","mstr_standard","I99";
;
CDS_LIB"mstr_standard"
BODY_TYPE"PLUMBING"
HDL_TAP"TRUE";
"B \NAC \NWC"9;
"S \NAC"
BN"7"74;
END.
